# T6G (Grand Teton) — schematic netlist excerpt (pin names and nets, part order shuffled) for the footprints in the layout excerpt that follows; sources: Cadence DE-HDL packaged netlist, KiCad conversion of 04192023_DAF0TMB3IC0_F0TG_MB_C_brd_V02_OCP.brd

C78  Q_CAP  0.1UF 25V 10% X7R  pkg 0402  page 182 : A = P3V3_9ZXL045_P0_VDDR ; B = GND
R1244  Q_RES  0 5% CHIP  pkg 0402LF  page 258 : A = SMB_ADC_SCL_R ; B = SMB_SEN_TIC_2_3V3AUX_SCL

(kicad_pcb
	(version 20260206)
	(generator "pcbnew")
	(generator_version "10.0")
	(general
		(thickness 1.6)
		(legacy_teardrops no)
	)
	(paper "A4")
	(title_block
		(title "04192023_DAF0TMB3IC0_F0TG_MB_C_brd_V02_OCP.brd")
		(comment 1 "Grand Teton / footprints 5557-5558 of 8354")
	)
	(layers
		(0 "F.Cu" signal "TOP")
		(4 "In1.Cu" signal "GND")
		(6 "In2.Cu" signal "IN1")
		(8 "In3.Cu" signal "GND1")
		(10 "In4.Cu" signal "IN2")
		(12 "In5.Cu" signal "GND2")
		(14 "In6.Cu" signal "IN3")
		(16 "In7.Cu" signal "GND3")
		(18 "In8.Cu" signal "VCC")
		(20 "In9.Cu" signal "VCC1")
		(22 "In10.Cu" signal "GND4")
		(24 "In11.Cu" signal "IN4")
		(26 "In12.Cu" signal "GND5")
		(28 "In13.Cu" signal "IN5")
		(30 "In14.Cu" signal "GND6")
		(32 "In15.Cu" signal "IN6")
		(34 "In16.Cu" signal "GND7")
		(2 "B.Cu" signal "BOTTOM")
		(9 "F.Adhes" user "F.Adhesive")
		(11 "B.Adhes" user "B.Adhesive")
		(13 "F.Paste" user "Package Geometry/Pastemask Top")
		(15 "B.Paste" user "Package Geometry/Pastemask Bottom")
		(5 "F.SilkS" user "Ref Des/Silkscreen Top")
		(7 "B.SilkS" user "Ref Des/Silkscreen Bottom")
		(1 "F.Mask" user "Board Geometry/Soldermask Top")
		(3 "B.Mask" user "Board Geometry/Soldermask Bottom")
		(17 "Dwgs.User" user "User.Drawings")
		(19 "Cmts.User" user "User.Comments")
		(21 "Eco1.User" user "User.Eco1")
		(23 "Eco2.User" user "User.Eco2")
		(25 "Edge.Cuts" user "Board Geometry/Outline")
		(27 "Margin" user)
		(31 "F.CrtYd" user "Package Geometry/Place Bound Top")
		(29 "B.CrtYd" user "Package Geometry/Place Bound Bottom")
		(35 "F.Fab" user "Ref Des/Assembly Top")
		(33 "B.Fab" user "Ref Des/Assembly Bottom")
	)
	(footprint ""
		(layer "B.Cu")
		(at 283.645356 -418.976302 180)
		(property "Reference" "C78"
			(at 0 0 0)
			(layer "B.SilkS")
			(hide yes)
			(effects
				(font
					(size 1.27 1.27)
				)
				(justify mirror)
			)
		)
		(property "Value" ""
			(at 0 0 0)
			(layer "B.Fab")
			(effects
				(font
					(size 1.27 1.27)
				)
				(justify mirror)
			)
		)
		(duplicate_pad_numbers_are_jumpers no)
		(fp_line
			(start 0.7874 0.4064)
			(end 0.7874 -0.4064)
			(stroke
				(width 0.1524)
				(type default)
			)
			(layer "B.SilkS")
		)
		(fp_line
			(start 0.7874 -0.4064)
			(end -0.7874 -0.4064)
			(stroke
				(width 0.1524)
				(type default)
			)
			(layer "B.SilkS")
		)
		(fp_line
			(start -0.7874 0.4064)
			(end 0.7874 0.4064)
			(stroke
				(width 0.1524)
				(type default)
			)
			(layer "B.SilkS")
		)
		(fp_line
			(start -0.7874 -0.4064)
			(end -0.7874 0.4064)
			(stroke
				(width 0.1524)
				(type default)
			)
			(layer "B.SilkS")
		)
		(fp_line
			(start 0.67945 0.3048)
			(end 0.67945 -0.305054)
			(stroke
				(width 0.1)
				(type default)
			)
			(layer "B.Fab")
		)
		(fp_line
			(start 0.67945 -0.305054)
			(end 0.12065 -0.305054)
			(stroke
				(width 0.1)
				(type default)
			)
			(layer "B.Fab")
		)
		(fp_line
			(start 0.12065 0.3048)
			(end 0.67945 0.3048)
			(stroke
				(width 0.1)
				(type default)
			)
			(layer "B.Fab")
		)
		(fp_line
			(start 0.12065 0.2794)
			(end 0.12065 0.3048)
			(stroke
				(width 0.1)
				(type default)
			)
			(layer "B.Fab")
		)
		(fp_line
			(start 0.12065 -0.2794)
			(end -0.12065 -0.2794)
			(stroke
				(width 0.1)
				(type default)
			)
			(layer "B.Fab")
		)
		(fp_line
			(start 0.12065 -0.305054)
			(end 0.12065 -0.2794)
			(stroke
				(width 0.1)
				(type default)
			)
			(layer "B.Fab")
		)
		(fp_line
			(start -0.120396 0.3048)
			(end -0.120396 0.2794)
			(stroke
				(width 0.1)
				(type default)
			)
			(layer "B.Fab")
		)
		(fp_line
			(start -0.120396 0.2794)
			(end 0.12065 0.2794)
			(stroke
				(width 0.1)
				(type default)
			)
			(layer "B.Fab")
		)
		(fp_line
			(start -0.12065 -0.2794)
			(end -0.12065 -0.3048)
			(stroke
				(width 0.1)
				(type default)
			)
			(layer "B.Fab")
		)
		(fp_line
			(start -0.12065 -0.3048)
			(end -0.67945 -0.3048)
			(stroke
				(width 0.1)
				(type default)
			)
			(layer "B.Fab")
		)
		(fp_line
			(start -0.67945 0.3048)
			(end -0.120396 0.3048)
			(stroke
				(width 0.1)
				(type default)
			)
			(layer "B.Fab")
		)
		(fp_line
			(start -0.67945 -0.3048)
			(end -0.67945 0.3048)
			(stroke
				(width 0.1)
				(type default)
			)
			(layer "B.Fab")
		)
		(pad "1" smd circle
			(at 0.40005 0)
			(size 0 0)
			(layers "B.Cu" "B.Mask" "B.Paste")
			(net "P3V3_9ZXL045_P0_VDDR")
		)
		(pad "2" smd circle
			(at -0.40005 0)
			(size 0 0)
			(layers "B.Cu" "B.Mask" "B.Paste")
			(net "GND")
		)
	)
	(footprint ""
		(layer "B.Cu")
		(at 216.10193 -324.647306 180)
		(property "Reference" "R1244"
			(at 0 0 0)
			(layer "B.SilkS")
			(hide yes)
			(effects
				(font
					(size 1.27 1.27)
				)
				(justify mirror)
			)
		)
		(property "Value" ""
			(at 0 0 0)
			(layer "B.Fab")
			(effects
				(font
					(size 1.27 1.27)
				)
				(justify mirror)
			)
		)
		(duplicate_pad_numbers_are_jumpers no)
		(fp_line
			(start 0.7874 0.4064)
			(end 0.7874 -0.4064)
			(stroke
				(width 0.1524)
				(type default)
			)
			(layer "B.SilkS")
		)
		(fp_line
			(start 0.7874 -0.4064)
			(end -0.7874 -0.4064)
			(stroke
				(width 0.1524)
				(type default)
			)
			(layer "B.SilkS")
		)
		(fp_line
			(start -0.7874 0.4064)
			(end 0.7874 0.4064)
			(stroke
				(width 0.1524)
				(type default)
			)
			(layer "B.SilkS")
		)
		(fp_line
			(start -0.7874 -0.4064)
			(end -0.7874 0.4064)
			(stroke
				(width 0.1524)
				(type default)
			)
			(layer "B.SilkS")
		)
		(fp_line
			(start 0.67945 0.3048)
			(end 0.67945 -0.305054)
			(stroke
				(width 0.1)
				(type default)
			)
			(layer "B.Fab")
		)
		(fp_line
			(start 0.67945 -0.305054)
			(end 0.12065 -0.305054)
			(stroke
				(width 0.1)
				(type default)
			)
			(layer "B.Fab")
		)
		(fp_line
			(start 0.12065 0.3048)
			(end 0.67945 0.3048)
			(stroke
				(width 0.1)
				(type default)
			)
			(layer "B.Fab")
		)
		(fp_line
			(start 0.12065 0.2794)
			(end 0.12065 0.3048)
			(stroke
				(width 0.1)
				(type default)
			)
			(layer "B.Fab")
		)
		(fp_line
			(start 0.12065 -0.2794)
			(end -0.12065 -0.2794)
			(stroke
				(width 0.1)
				(type default)
			)
			(layer "B.Fab")
		)
		(fp_line
			(start 0.12065 -0.305054)
			(end 0.12065 -0.2794)
			(stroke
				(width 0.1)
				(type default)
			)
			(layer "B.Fab")
		)
		(fp_line
			(start -0.120396 0.3048)
			(end -0.120396 0.2794)
			(stroke
				(width 0.1)
				(type default)
			)
			(layer "B.Fab")
		)
		(fp_line
			(start -0.120396 0.2794)
			(end 0.12065 0.2794)
			(stroke
				(width 0.1)
				(type default)
			)
			(layer "B.Fab")
		)
		(fp_line
			(start -0.12065 -0.2794)
			(end -0.12065 -0.3048)
			(stroke
				(width 0.1)
				(type default)
			)
			(layer "B.Fab")
		)
		(fp_line
			(start -0.12065 -0.3048)
			(end -0.67945 -0.3048)
			(stroke
				(width 0.1)
				(type default)
			)
			(layer "B.Fab")
		)
		(fp_line
			(start -0.67945 0.3048)
			(end -0.120396 0.3048)
			(stroke
				(width 0.1)
				(type default)
			)
			(layer "B.Fab")
		)
		(fp_line
			(start -0.67945 -0.3048)
			(end -0.67945 0.3048)
			(stroke
				(width 0.1)
				(type default)
			)
			(layer "B.Fab")
		)
		(pad "1" smd circle
			(at 0.40005 0)
			(size 0 0)
			(layers "B.Cu" "B.Mask" "B.Paste")
			(net "SMB_ADC_SCL_R")
		)
		(pad "2" smd circle
			(at -0.40005 0)
			(size 0 0)
			(layers "B.Cu" "B.Mask" "B.Paste")
			(net "SMB_SEN_TIC_2_3V3AUX_SCL")
		)
	)
)
